#ISCELL
  pure_quanta quanta_title_block_c *
  *
#ISCELL
  standard offpage *
  page165_i1
#ISCELL
  standard tap *
  page165_i10
#ISCELL
  standard tap *
  page165_i100
#ISCELL
  standard tap *
  page165_i101
#ISCELL
  standard tap *
  page165_i102
#ISCELL
  standard tap *
  page165_i103
#ISCELL
  standard tap *
  page165_i104
#ISCELL
  standard offpage *
  page165_i105
#ISCELL
  standard offpage *
  page165_i106
#ISCELL
  standard offpage *
  page165_i107
#ISCELL
  standard offpage *
  page165_i108
#ISCELL
  standard tap *
  page165_i109
#ISCELL
  standard tap *
  page165_i11
#ISCELL
  standard tap *
  page165_i110
#ISCELL
  standard tap *
  page165_i111
#ISCELL
  standard tap *
  page165_i112
#ISCELL
  standard tap *
  page165_i113
#ISCELL
  standard tap *
  page165_i114
#ISCELL
  standard tap *
  page165_i115
#ISCELL
  standard tap *
  page165_i116
#ISCELL
  standard tap *
  page165_i117
#ISCELL
  standard tap *
  page165_i118
#ISCELL
  standard tap *
  page165_i119
#ISCELL
  standard tap *
  page165_i12
#CELL
  pure_quanta q_cap_diffbus *
  page165_i120
#CELL
  pure_quanta q_cap_diffbus *
  page165_i121
#CELL
  pure_quanta q_cap_diffbus *
  page165_i122
#CELL
  pure_quanta q_cap_diffbus *
  page165_i123
#CELL
  pure_quanta q_cap_diffbus *
  page165_i124
#CELL
  pure_quanta q_cap_diffbus *
  page165_i125
#CELL
  pure_quanta q_cap_diffbus *
  page165_i126
#CELL
  pure_quanta q_cap_diffbus *
  page165_i127
#CELL
  pure_quanta q_cap_diffbus *
  page165_i128
#ISCELL
  standard tap *
  page165_i129
#ISCELL
  standard tap *
  page165_i13
#ISCELL
  standard tap *
  page165_i130
#ISCELL
  standard tap *
  page165_i131
#CELL
  pure_quanta q_cap_diffbus *
  page165_i132
#CELL
  pure_quanta q_cap_diffbus *
  page165_i133
#CELL
  pure_quanta q_cap_diffbus *
  page165_i134
#CELL
  pure_quanta q_cap_diffbus *
  page165_i135
#CELL
  pure_quanta q_cap_diffbus *
  page165_i136
#CELL
  pure_quanta q_cap_diffbus *
  page165_i137
#ISCELL
  standard tap *
  page165_i138
#ISCELL
  standard tap *
  page165_i139
#ISCELL
  standard tap *
  page165_i14
#ISCELL
  standard tap *
  page165_i140
#ISCELL
  standard tap *
  page165_i141
#ISCELL
  standard tap *
  page165_i142
#ISCELL
  standard tap *
  page165_i143
#ISCELL
  standard tap *
  page165_i144
#ISCELL
  standard tap *
  page165_i145
#ISCELL
  standard tap *
  page165_i146
#ISCELL
  standard tap *
  page165_i147
#ISCELL
  standard tap *
  page165_i148
#ISCELL
  standard tap *
  page165_i149
#ISCELL
  standard tap *
  page165_i15
#ISCELL
  standard tap *
  page165_i150
#CELL
  pure_quanta q_cap_diffbus *
  page165_i151
#CELL
  pure_quanta q_cap_diffbus *
  page165_i152
#CELL
  pure_quanta q_cap_diffbus *
  page165_i153
#CELL
  pure_quanta q_cap_diffbus *
  page165_i154
#CELL
  pure_quanta q_cap_diffbus *
  page165_i155
#CELL
  pure_quanta q_cap_diffbus *
  page165_i156
#CELL
  pure_quanta q_cap_diffbus *
  page165_i157
#CELL
  pure_quanta q_cap_diffbus *
  page165_i158
#CELL
  pure_quanta q_cap_diffbus *
  page165_i159
#ISCELL
  standard tap *
  page165_i16
#CELL
  pure_quanta q_cap_diffbus *
  page165_i160
#ISCELL
  standard tap *
  page165_i161
#ISCELL
  standard tap *
  page165_i162
#ISCELL
  standard tap *
  page165_i163
#CELL
  pure_quanta q_cap_diffbus *
  page165_i164
#CELL
  pure_quanta q_cap_diffbus *
  page165_i165
#CELL
  pure_quanta q_cap_diffbus *
  page165_i166
#CELL
  pure_quanta q_cap_diffbus *
  page165_i167
#CELL
  pure_quanta q_cap_diffbus *
  page165_i168
#CELL
  pure_quanta q_cap_diffbus *
  page165_i169
#ISCELL
  standard tap *
  page165_i17
#ISCELL
  standard tap *
  page165_i170
#ISCELL
  standard tap *
  page165_i171
#ISCELL
  standard tap *
  page165_i172
#ISCELL
  standard tap *
  page165_i173
#ISCELL
  standard tap *
  page165_i174
#ISCELL
  standard tap *
  page165_i175
#ISCELL
  standard tap *
  page165_i176
#ISCELL
  standard tap *
  page165_i177
#ISCELL
  standard tap *
  page165_i178
#ISCELL
  standard tap *
  page165_i179
#ISCELL
  standard tap *
  page165_i18
#ISCELL
  standard tap *
  page165_i180
#ISCELL
  standard tap *
  page165_i181
#ISCELL
  standard tap *
  page165_i182
#ISCELL
  standard tap *
  page165_i183
#ISCELL
  standard tap *
  page165_i184
#ISCELL
  standard tap *
  page165_i185
#ISCELL
  standard offpage *
  page165_i186
#ISCELL
  standard offpage *
  page165_i187
#ISCELL
  standard tap *
  page165_i188
#ISCELL
  standard tap *
  page165_i189
#ISCELL
  standard tap *
  page165_i19
#ISCELL
  standard tap *
  page165_i190
#ISCELL
  standard tap *
  page165_i191
#ISCELL
  standard tap *
  page165_i192
#ISCELL
  standard tap *
  page165_i193
#ISCELL
  standard tap *
  page165_i194
#ISCELL
  standard tap *
  page165_i195
#ISCELL
  standard tap *
  page165_i196
#ISCELL
  standard tap *
  page165_i197
#ISCELL
  standard tap *
  page165_i198
#ISCELL
  standard tap *
  page165_i199
#ISCELL
  standard offpage *
  page165_i2
#ISCELL
  standard tap *
  page165_i20
#ISCELL
  standard tap *
  page165_i200
#ISCELL
  standard tap *
  page165_i201
#ISCELL
  standard tap *
  page165_i202
#ISCELL
  standard tap *
  page165_i203
#ISCELL
  standard offpage *
  page165_i204
#ISCELL
  standard offpage *
  page165_i205
#CELL
  pure_quanta q_cap_diffbus *
  page165_i206
#ISCELL
  standard tap *
  page165_i207
#ISCELL
  standard tap *
  page165_i208
#CELL
  pure_quanta q_cap_diffbus *
  page165_i21
#CELL
  pure_quanta q_cap_diffbus *
  page165_i22
#CELL
  pure_quanta q_cap_diffbus *
  page165_i23
#CELL
  pure_quanta q_cap_diffbus *
  page165_i24
#CELL
  pure_quanta q_cap_diffbus *
  page165_i25
#CELL
  pure_quanta q_cap_diffbus *
  page165_i26
#CELL
  pure_quanta q_cap_diffbus *
  page165_i27
#CELL
  pure_quanta q_cap_diffbus *
  page165_i28
#CELL
  pure_quanta q_cap_diffbus *
  page165_i29
#ISCELL
  standard offpage *
  page165_i3
#CELL
  pure_quanta q_cap_diffbus *
  page165_i30
#ISCELL
  standard tap *
  page165_i31
#ISCELL
  standard tap *
  page165_i32
#ISCELL
  standard tap *
  page165_i33
#ISCELL
  standard tap *
  page165_i34
#ISCELL
  standard tap *
  page165_i35
#CELL
  pure_quanta q_cap_diffbus *
  page165_i36
#CELL
  pure_quanta q_cap_diffbus *
  page165_i37
#CELL
  pure_quanta q_cap_diffbus *
  page165_i38
#CELL
  pure_quanta q_cap_diffbus *
  page165_i39
#ISCELL
  standard offpage *
  page165_i4
#CELL
  pure_quanta q_cap_diffbus *
  page165_i40
#CELL
  pure_quanta q_cap_diffbus *
  page165_i41
#ISCELL
  standard tap *
  page165_i42
#ISCELL
  standard tap *
  page165_i43
#ISCELL
  standard tap *
  page165_i44
#ISCELL
  standard tap *
  page165_i45
#ISCELL
  standard tap *
  page165_i46
#ISCELL
  standard tap *
  page165_i47
#ISCELL
  standard tap *
  page165_i48
#ISCELL
  standard tap *
  page165_i49
#ISCELL
  standard tap *
  page165_i5
#ISCELL
  standard tap *
  page165_i50
#ISCELL
  standard tap *
  page165_i51
#ISCELL
  standard tap *
  page165_i52
#ISCELL
  standard tap *
  page165_i53
#ISCELL
  standard tap *
  page165_i54
#ISCELL
  standard tap *
  page165_i55
#ISCELL
  standard tap *
  page165_i56
#ISCELL
  standard tap *
  page165_i57
#ISCELL
  standard tap *
  page165_i58
#ISCELL
  standard tap *
  page165_i59
#ISCELL
  standard tap *
  page165_i6
#ISCELL
  standard tap *
  page165_i60
#CELL
  pure_quanta q_cap_diffbus *
  page165_i61
#CELL
  pure_quanta q_cap_diffbus *
  page165_i62
#CELL
  pure_quanta q_cap_diffbus *
  page165_i63
#CELL
  pure_quanta q_cap_diffbus *
  page165_i64
#CELL
  pure_quanta q_cap_diffbus *
  page165_i65
#CELL
  pure_quanta q_cap_diffbus *
  page165_i66
#CELL
  pure_quanta q_cap_diffbus *
  page165_i67
#CELL
  pure_quanta q_cap_diffbus *
  page165_i68
#CELL
  pure_quanta q_cap_diffbus *
  page165_i69
#ISCELL
  standard tap *
  page165_i7
#CELL
  pure_quanta q_cap_diffbus *
  page165_i70
#ISCELL
  standard tap *
  page165_i71
#ISCELL
  standard tap *
  page165_i72
#ISCELL
  standard tap *
  page165_i73
#ISCELL
  standard tap *
  page165_i74
#ISCELL
  standard tap *
  page165_i75
#CELL
  pure_quanta q_cap_diffbus *
  page165_i76
#CELL
  pure_quanta q_cap_diffbus *
  page165_i77
#CELL
  pure_quanta q_cap_diffbus *
  page165_i78
#CELL
  pure_quanta q_cap_diffbus *
  page165_i79
#ISCELL
  standard tap *
  page165_i8
#CELL
  pure_quanta q_cap_diffbus *
  page165_i80
#CELL
  pure_quanta q_cap_diffbus *
  page165_i81
#ISCELL
  standard tap *
  page165_i82
#ISCELL
  standard tap *
  page165_i83
#ISCELL
  standard tap *
  page165_i84
#ISCELL
  standard tap *
  page165_i85
#ISCELL
  standard tap *
  page165_i86
#ISCELL
  standard tap *
  page165_i87
#ISCELL
  standard tap *
  page165_i88
#ISCELL
  standard tap *
  page165_i89
#ISCELL
  standard tap *
  page165_i9
#ISCELL
  standard tap *
  page165_i90
#ISCELL
  standard tap *
  page165_i91
#ISCELL
  standard tap *
  page165_i92
#ISCELL
  standard offpage *
  page165_i93
#ISCELL
  standard offpage *
  page165_i94
#ISCELL
  standard offpage *
  page165_i95
#ISCELL
  standard offpage *
  page165_i96
#ISCELL
  standard tap *
  page165_i97
#ISCELL
  standard tap *
  page165_i98
#ISCELL
  standard tap *
  page165_i99
